(kicad_pcb
	(version 20241229)
	(generator "pcbnew")
	(generator_version "9.0")
	(general
		(thickness 1.61)
		(legacy_teardrops no)
	)
	(paper "A3")
	(title_block
		(title "SO-DIMM DDR5 Tester")
		(date "2025-11-26")
		(rev "1.3.0")
		(comment 9 "footprints 573-579 of 627")
	)
	(layers
		(0 "F.Cu" signal)
		(4 "In1.Cu" power)
		(6 "In2.Cu" mixed)
		(8 "In3.Cu" power)
		(10 "In4.Cu" mixed)
		(12 "In5.Cu" power)
		(14 "In6.Cu" mixed)
		(16 "In7.Cu" power)
		(18 "In8.Cu" power)
		(20 "In9.Cu" mixed)
		(22 "In10.Cu" power)
		(2 "B.Cu" signal)
		(9 "F.Adhes" user "F.Adhesive")
		(11 "B.Adhes" user "B.Adhesive")
		(13 "F.Paste" user)
		(15 "B.Paste" user)
		(5 "F.SilkS" user "F.Silkscreen")
		(7 "B.SilkS" user "B.Silkscreen")
		(1 "F.Mask" user)
		(3 "B.Mask" user)
		(17 "Dwgs.User" user "User.Drawings")
		(19 "Cmts.User" user "User.Comments")
		(21 "Eco1.User" user "User.Eco1")
		(23 "Eco2.User" user "User.Eco2")
		(25 "Edge.Cuts" user)
		(27 "Margin" user)
		(31 "F.CrtYd" user "F.Courtyard")
		(29 "B.CrtYd" user "B.Courtyard")
		(35 "F.Fab" user)
		(33 "B.Fab" user)
	)
	(footprint "antmicro-footprints:R_0402_1005Metric"
		(layer "B.Cu")
		(at 180.8 199.4 180)
		(descr "Resistor SMD 0402")
		(tags "resistor SMD 0402")
		(property "Reference" "R176"
			(at -3.95 -0.5 0)
			(layer "B.SilkS")
			(effects
				(font
					(size 0.7 0.7)
					(thickness 0.15)
				)
				(justify left bottom mirror)
			)
		)
		(property "Value" "R_0R_0402"
			(at -1.011843 -1.772047 0)
			(layer "B.Fab")
			(effects
				(font
					(size 0.7 0.7)
					(thickness 0.15)
				)
				(justify left bottom mirror)
			)
		)
		(property "Datasheet" "https://industrial.panasonic.com/cdbs/www-data/pdf/RDA0000/AOA0000C301.pdf"
			(at 0 0 180)
			(layer "F.Fab")
			(hide yes)
			(effects
				(font
					(size 1.27 1.27)
					(thickness 0.15)
				)
			)
		)
		(property "Author" "Antmicro"
			(at 361.6 398.8 0)
			(layer "B.Fab")
			(hide yes)
			(effects
				(font
					(size 1 1)
					(thickness 0.15)
				)
				(justify mirror)
			)
		)
		(property "Current" "1A"
			(at 361.6 398.8 0)
			(layer "B.Fab")
			(hide yes)
			(effects
				(font
					(size 1 1)
					(thickness 0.15)
				)
				(justify mirror)
			)
		)
		(property "License" "Apache-2.0"
			(at 361.6 398.8 0)
			(layer "B.Fab")
			(hide yes)
			(effects
				(font
					(size 1 1)
					(thickness 0.15)
				)
				(justify mirror)
			)
		)
		(property "MPN" "ERJ2GE0R00X"
			(at 361.6 398.8 0)
			(layer "B.Fab")
			(hide yes)
			(effects
				(font
					(size 1 1)
					(thickness 0.15)
				)
				(justify mirror)
			)
		)
		(property "Manufacturer" "Panasonic"
			(at 361.6 398.8 0)
			(layer "B.Fab")
			(hide yes)
			(effects
				(font
					(size 1 1)
					(thickness 0.15)
				)
				(justify mirror)
			)
		)
		(property "Tolerance" ""
			(at 361.6 398.8 0)
			(layer "B.Fab")
			(hide yes)
			(effects
				(font
					(size 1 1)
					(thickness 0.15)
				)
				(justify mirror)
			)
		)
		(property "Val" "0R"
			(at 361.6 398.8 0)
			(layer "B.Fab")
			(hide yes)
			(effects
				(font
					(size 1 1)
					(thickness 0.15)
				)
				(justify mirror)
			)
		)
		(sheetname "/I^{2}C/")
		(sheetfile "i2c.kicad_sch")
		(attr exclude_from_pos_files exclude_from_bom dnp)
		(fp_rect
			(start -0.93 0.47)
			(end 0.93 -0.47)
			(stroke
				(width 0.05)
				(type solid)
			)
			(fill no)
			(layer "B.CrtYd")
		)
		(fp_rect
			(start -0.5 0.25)
			(end 0.5 -0.25)
			(stroke
				(width 0.15)
				(type solid)
			)
			(fill no)
			(layer "B.Fab")
		)
		(pad "1" smd roundrect
			(at -0.485 0 180)
			(size 0.59 0.64)
			(layers "B.Cu" "B.Mask" "B.Paste")
			(roundrect_rratio 0.25)
			(net 690 "/I^{2}C/PWR.SDA")
			(pintype "passive")
		)
		(pad "2" smd roundrect
			(at 0.485 0 180)
			(size 0.59 0.64)
			(layers "B.Cu" "B.Mask" "B.Paste")
			(roundrect_rratio 0.25)
			(net 672 "/Debug FTDI/FTDI.SDA")
			(pintype "passive")
		)
	)
	(footprint "antmicro-footprints:TP_SMD_1mm"
		(layer "B.Cu")
		(at 110 179.13 180)
		(property "Reference" "TP49"
			(at -3.4 -0.45 0)
			(layer "B.SilkS")
			(effects
				(font
					(size 0.7 0.7)
					(thickness 0.15)
				)
				(justify left bottom mirror)
			)
		)
		(property "Value" "TP_1mm_SMD"
			(at 0 -1.4 0)
			(layer "B.Fab")
			(effects
				(font
					(size 0.7 0.7)
					(thickness 0.15)
				)
				(justify left bottom mirror)
			)
		)
		(property "MPN" ""
			(at 0 0 0)
			(unlocked yes)
			(layer "B.Fab")
			(hide yes)
			(effects
				(font
					(size 1 1)
					(thickness 0.15)
				)
				(justify mirror)
			)
		)
		(property "Manufacturer" ""
			(at 0 0 0)
			(unlocked yes)
			(layer "B.Fab")
			(hide yes)
			(effects
				(font
					(size 1 1)
					(thickness 0.15)
				)
				(justify mirror)
			)
		)
		(property "Author" "Antmicro"
			(at 0 0 0)
			(unlocked yes)
			(layer "B.Fab")
			(hide yes)
			(effects
				(font
					(size 1 1)
					(thickness 0.15)
				)
				(justify mirror)
			)
		)
		(property "License" "Apache-2.0"
			(at 0 0 0)
			(unlocked yes)
			(layer "B.Fab")
			(hide yes)
			(effects
				(font
					(size 1 1)
					(thickness 0.15)
				)
				(justify mirror)
			)
		)
		(sheetname "/Debug FTDI/")
		(sheetfile "debug-ftdi.kicad_sch")
		(attr exclude_from_pos_files)
		(fp_circle
			(center 0 0)
			(end 0.6 0)
			(stroke
				(width 0.05)
				(type default)
			)
			(fill no)
			(layer "B.CrtYd")
		)
		(fp_text user "License: Apache-2.0"
			(at -0.5 -5.2 0)
			(layer "B.Fab")
			(effects
				(font
					(size 0.7 0.7)
					(thickness 0.15)
				)
				(justify left bottom mirror)
			)
		)
		(fp_text user "Author: Antmicro"
			(at -0.5 -4 0)
			(layer "B.Fab")
			(effects
				(font
					(size 0.7 0.7)
					(thickness 0.15)
				)
				(justify left bottom mirror)
			)
		)
		(fp_text user "${REFERENCE}"
			(at -0.5 -2.8 0)
			(layer "B.Fab")
			(effects
				(font
					(size 0.7 0.7)
					(thickness 0.15)
				)
				(justify left bottom mirror)
			)
		)
		(pad "1" smd circle
			(at 0 0 180)
			(size 1 1)
			(layers "B.Cu" "B.Mask")
			(net 639 "/Debug FTDI/UART0.RX")
			(pinfunction "1")
			(pintype "passive")
		)
	)
	(footprint "antmicro-footprints:C_0402_1005Metric"
		(layer "B.Cu")
		(at 142.375501 177.801 90)
		(descr "Capacitor SMD 0402 (1005 Metric), square (rectangular) end terminal, IPC_7351 nominal, (Body size source: IPC-SM-782 page 76, https://www.pcb-3d.com/wordpress/wp-content/uploads/ipc-sm-782a_amendment_1_and_2.pdf)")
		(tags "capacitor 0402")
		(property "Reference" "C68"
			(at 0 1.17 270)
			(layer "B.SilkS")
			(hide yes)
			(effects
				(font
					(size 0.7 0.7)
					(thickness 0.15)
				)
				(justify left bottom mirror)
			)
		)
		(property "Value" "C_100n_0402"
			(at 0 -1.169 270)
			(layer "B.Fab")
			(effects
				(font
					(size 0.7 0.7)
					(thickness 0.15)
				)
				(justify left bottom mirror)
			)
		)
		(property "Datasheet" "https://www.murata.com/products/productdetail?partno=GRM155R61H104KE14%23"
			(at 0 0 90)
			(layer "F.Fab")
			(hide yes)
			(effects
				(font
					(size 1.27 1.27)
					(thickness 0.15)
				)
			)
		)
		(property "Author" "Antmicro"
			(at 320.176501 35.425499 0)
			(layer "B.Fab")
			(hide yes)
			(effects
				(font
					(size 1 1)
					(thickness 0.15)
				)
				(justify mirror)
			)
		)
		(property "Dielectric" "X5R"
			(at 320.176501 35.425499 0)
			(layer "B.Fab")
			(hide yes)
			(effects
				(font
					(size 1 1)
					(thickness 0.15)
				)
				(justify mirror)
			)
		)
		(property "License" "Apache-2.0"
			(at 320.176501 35.425499 0)
			(layer "B.Fab")
			(hide yes)
			(effects
				(font
					(size 1 1)
					(thickness 0.15)
				)
				(justify mirror)
			)
		)
		(property "MPN" "GRM155R61H104KE14D"
			(at 320.176501 35.425499 0)
			(layer "B.Fab")
			(hide yes)
			(effects
				(font
					(size 1 1)
					(thickness 0.15)
				)
				(justify mirror)
			)
		)
		(property "Manufacturer" "Murata"
			(at 320.176501 35.425499 0)
			(layer "B.Fab")
			(hide yes)
			(effects
				(font
					(size 1 1)
					(thickness 0.15)
				)
				(justify mirror)
			)
		)
		(property "Val" "100n"
			(at 320.176501 35.425499 0)
			(layer "B.Fab")
			(hide yes)
			(effects
				(font
					(size 1 1)
					(thickness 0.15)
				)
				(justify mirror)
			)
		)
		(property "Voltage" "50V"
			(at 320.176501 35.425499 0)
			(layer "B.Fab")
			(hide yes)
			(effects
				(font
					(size 1 1)
					(thickness 0.15)
				)
				(justify mirror)
			)
		)
		(sheetname "/FPGA power/")
		(sheetfile "fpga-power.kicad_sch")
		(attr smd)
		(fp_rect
			(start -0.9656 0.4572)
			(end 0.9652 -0.4828)
			(stroke
				(width 0.05)
				(type solid)
			)
			(fill no)
			(layer "B.CrtYd")
		)
		(fp_line
			(start 0.498 -0.248)
			(end -0.5 -0.248)
			(stroke
				(width 0.15)
				(type solid)
			)
			(layer "B.Fab")
		)
		(fp_line
			(start -0.5 -0.248)
			(end -0.5 0.25)
			(stroke
				(width 0.15)
				(type solid)
			)
			(layer "B.Fab")
		)
		(fp_line
			(start 0.498 0.25)
			(end 0.498 -0.248)
			(stroke
				(width 0.15)
				(type solid)
			)
			(layer "B.Fab")
		)
		(fp_line
			(start -0.5 0.25)
			(end 0.498 0.25)
			(stroke
				(width 0.15)
				(type solid)
			)
			(layer "B.Fab")
		)
		(pad "1" smd roundrect
			(at -0.5 0)
			(size 0.6 0.6)
			(layers "B.Cu" "B.Mask" "B.Paste")
			(roundrect_rratio 0.25)
			(net 1 "GND")
			(pintype "passive")
		)
		(pad "2" smd roundrect
			(at 0.498 0 90)
			(size 0.6 0.6)
			(layers "B.Cu" "B.Mask" "B.Paste")
			(roundrect_rratio 0.25)
			(net 188 "+1V8")
			(pintype "passive")
		)
	)
	(footprint "antmicro-footprints:C_0402_1005Metric"
		(layer "B.Cu")
		(at 82.856897 137.670037 -90)
		(descr "Capacitor SMD 0402")
		(tags "capacitor SMD 0402")
		(property "Reference" "C135"
			(at 0 0.699 90)
			(layer "B.SilkS")
			(hide yes)
			(effects
				(font
					(size 0.7 0.7)
					(thickness 0.15)
				)
				(justify left bottom mirror)
			)
		)
		(property "Value" "C_100n_0402"
			(at -1.022927 -2.155213 90)
			(layer "B.Fab")
			(effects
				(font
					(size 0.7 0.7)
					(thickness 0.15)
				)
				(justify left bottom mirror)
			)
		)
		(property "Datasheet" "https://www.murata.com/products/productdetail?partno=GRM155R61H104KE14%23"
			(at 0 0 270)
			(layer "F.Fab")
			(hide yes)
			(effects
				(font
					(size 1.27 1.27)
					(thickness 0.15)
				)
			)
		)
		(property "Author" "Antmicro"
			(at -52.25659 217.970384 0)
			(layer "B.Fab")
			(hide yes)
			(effects
				(font
					(size 1 1)
					(thickness 0.15)
				)
				(justify mirror)
			)
		)
		(property "Dielectric" "X5R"
			(at -52.25659 217.970384 0)
			(layer "B.Fab")
			(hide yes)
			(effects
				(font
					(size 1 1)
					(thickness 0.15)
				)
				(justify mirror)
			)
		)
		(property "License" "Apache-2.0"
			(at -52.25659 217.970384 0)
			(layer "B.Fab")
			(hide yes)
			(effects
				(font
					(size 1 1)
					(thickness 0.15)
				)
				(justify mirror)
			)
		)
		(property "MPN" "GRM155R61H104KE14D"
			(at -52.25659 217.970384 0)
			(layer "B.Fab")
			(hide yes)
			(effects
				(font
					(size 1 1)
					(thickness 0.15)
				)
				(justify mirror)
			)
		)
		(property "Manufacturer" "Murata"
			(at -52.25659 217.970384 0)
			(layer "B.Fab")
			(hide yes)
			(effects
				(font
					(size 1 1)
					(thickness 0.15)
				)
				(justify mirror)
			)
		)
		(property "Val" "100n"
			(at -52.25659 217.970384 0)
			(layer "B.Fab")
			(hide yes)
			(effects
				(font
					(size 1 1)
					(thickness 0.15)
				)
				(justify mirror)
			)
		)
		(property "Voltage" "50V"
			(at -52.25659 217.970384 0)
			(layer "B.Fab")
			(hide yes)
			(effects
				(font
					(size 1 1)
					(thickness 0.15)
				)
				(justify mirror)
			)
		)
		(sheetname "/Ethernet/")
		(sheetfile "ethernet.kicad_sch")
		(attr smd)
		(fp_rect
			(start -0.9659 0.481258)
			(end 0.9649 -0.458742)
			(stroke
				(width 0.05)
				(type solid)
			)
			(fill no)
			(layer "B.CrtYd")
		)
		(fp_line
			(start -0.499 0.25)
			(end 0.499 0.25)
			(stroke
				(width 0.15)
				(type solid)
			)
			(layer "B.Fab")
		)
		(fp_line
			(start 0.499 0.25)
			(end 0.499 -0.248)
			(stroke
				(width 0.15)
				(type solid)
			)
			(layer "B.Fab")
		)
		(fp_line
			(start -0.499 -0.248)
			(end -0.499 0.25)
			(stroke
				(width 0.15)
				(type solid)
			)
			(layer "B.Fab")
		)
		(fp_line
			(start 0.499 -0.248)
			(end -0.499 -0.248)
			(stroke
				(width 0.15)
				(type solid)
			)
			(layer "B.Fab")
		)
		(pad "1" smd roundrect
			(at -0.484 0 270)
			(size 0.59 0.64)
			(layers "B.Cu" "B.Mask" "B.Paste")
			(roundrect_rratio 0.25)
			(net 1 "GND")
			(pintype "passive")
		)
		(pad "2" smd roundrect
			(at 0.484 0 270)
			(size 0.59 0.64)
			(layers "B.Cu" "B.Mask" "B.Paste")
			(roundrect_rratio 0.25)
			(net 214 "Net-(C135-Pad2)")
			(pintype "passive")
		)
	)
	(footprint "antmicro-footprints:TP_SMD_1mm"
		(layer "B.Cu")
		(at 110 176.63 180)
		(property "Reference" "TP48"
			(at -3.3 -0.47 0)
			(layer "B.SilkS")
			(effects
				(font
					(size 0.7 0.7)
					(thickness 0.15)
				)
				(justify left bottom mirror)
			)
		)
		(property "Value" "TP_1mm_SMD"
			(at 0 -1.4 0)
			(layer "B.Fab")
			(effects
				(font
					(size 0.7 0.7)
					(thickness 0.15)
				)
				(justify left bottom mirror)
			)
		)
		(property "MPN" ""
			(at 0 0 0)
			(unlocked yes)
			(layer "B.Fab")
			(hide yes)
			(effects
				(font
					(size 1 1)
					(thickness 0.15)
				)
				(justify mirror)
			)
		)
		(property "Manufacturer" ""
			(at 0 0 0)
			(unlocked yes)
			(layer "B.Fab")
			(hide yes)
			(effects
				(font
					(size 1 1)
					(thickness 0.15)
				)
				(justify mirror)
			)
		)
		(property "Author" "Antmicro"
			(at 0 0 0)
			(unlocked yes)
			(layer "B.Fab")
			(hide yes)
			(effects
				(font
					(size 1 1)
					(thickness 0.15)
				)
				(justify mirror)
			)
		)
		(property "License" "Apache-2.0"
			(at 0 0 0)
			(unlocked yes)
			(layer "B.Fab")
			(hide yes)
			(effects
				(font
					(size 1 1)
					(thickness 0.15)
				)
				(justify mirror)
			)
		)
		(sheetname "/Debug FTDI/")
		(sheetfile "debug-ftdi.kicad_sch")
		(attr exclude_from_pos_files)
		(fp_circle
			(center 0 0)
			(end 0.6 0)
			(stroke
				(width 0.05)
				(type default)
			)
			(fill no)
			(layer "B.CrtYd")
		)
		(fp_text user "Author: Antmicro"
			(at -0.5 -4 0)
			(layer "B.Fab")
			(effects
				(font
					(size 0.7 0.7)
					(thickness 0.15)
				)
				(justify left bottom mirror)
			)
		)
		(fp_text user "${REFERENCE}"
			(at -0.5 -2.8 0)
			(layer "B.Fab")
			(effects
				(font
					(size 0.7 0.7)
					(thickness 0.15)
				)
				(justify left bottom mirror)
			)
		)
		(fp_text user "License: Apache-2.0"
			(at -0.5 -5.2 0)
			(layer "B.Fab")
			(effects
				(font
					(size 0.7 0.7)
					(thickness 0.15)
				)
				(justify left bottom mirror)
			)
		)
		(pad "1" smd circle
			(at 0 0 180)
			(size 1 1)
			(layers "B.Cu" "B.Mask")
			(net 641 "/Debug FTDI/UART0.TX")
			(pinfunction "1")
			(pintype "passive")
		)
	)
	(footprint "antmicro-footprints:TP_SMD_1mm"
		(layer "B.Cu")
		(at 95 188.275 180)
		(property "Reference" "TP44"
			(at -1.3 0.775 0)
			(layer "B.SilkS")
			(effects
				(font
					(size 0.7 0.7)
					(thickness 0.15)
				)
				(justify left bottom mirror)
			)
		)
		(property "Value" "TP_1mm_SMD"
			(at 0 -1.4 0)
			(layer "B.Fab")
			(effects
				(font
					(size 0.7 0.7)
					(thickness 0.15)
				)
				(justify left bottom mirror)
			)
		)
		(property "MPN" ""
			(at 0 0 0)
			(unlocked yes)
			(layer "B.Fab")
			(hide yes)
			(effects
				(font
					(size 1 1)
					(thickness 0.15)
				)
				(justify mirror)
			)
		)
		(property "Manufacturer" ""
			(at 0 0 0)
			(unlocked yes)
			(layer "B.Fab")
			(hide yes)
			(effects
				(font
					(size 1 1)
					(thickness 0.15)
				)
				(justify mirror)
			)
		)
		(property "Author" "Antmicro"
			(at 0 0 0)
			(unlocked yes)
			(layer "B.Fab")
			(hide yes)
			(effects
				(font
					(size 1 1)
					(thickness 0.15)
				)
				(justify mirror)
			)
		)
		(property "License" "Apache-2.0"
			(at 0 0 0)
			(unlocked yes)
			(layer "B.Fab")
			(hide yes)
			(effects
				(font
					(size 1 1)
					(thickness 0.15)
				)
				(justify mirror)
			)
		)
		(sheetname "/Debug FTDI/")
		(sheetfile "debug-ftdi.kicad_sch")
		(attr exclude_from_pos_files)
		(fp_circle
			(center 0 0)
			(end 0.6 0)
			(stroke
				(width 0.05)
				(type default)
			)
			(fill no)
			(layer "B.CrtYd")
		)
		(fp_text user "Author: Antmicro"
			(at -0.5 -4 0)
			(layer "B.Fab")
			(effects
				(font
					(size 0.7 0.7)
					(thickness 0.15)
				)
				(justify left bottom mirror)
			)
		)
		(fp_text user "${REFERENCE}"
			(at -0.5 -2.8 0)
			(layer "B.Fab")
			(effects
				(font
					(size 0.7 0.7)
					(thickness 0.15)
				)
				(justify left bottom mirror)
			)
		)
		(fp_text user "License: Apache-2.0"
			(at -0.5 -5.2 0)
			(layer "B.Fab")
			(effects
				(font
					(size 0.7 0.7)
					(thickness 0.15)
				)
				(justify left bottom mirror)
			)
		)
		(pad "1" smd circle
			(at 0 0 180)
			(size 1 1)
			(layers "B.Cu" "B.Mask")
			(net 48 "/Debug FTDI/JTAG.TDI")
			(pinfunction "1")
			(pintype "passive")
		)
	)
	(footprint "antmicro-footprints:C_0402_1005Metric"
		(layer "B.Cu")
		(at 141.875501 173.301 180)
		(descr "Capacitor SMD 0402 (1005 Metric), square (rectangular) end terminal, IPC_7351 nominal, (Body size source: IPC-SM-782 page 76, https://www.pcb-3d.com/wordpress/wp-content/uploads/ipc-sm-782a_amendment_1_and_2.pdf)")
		(tags "capacitor 0402")
		(property "Reference" "C43"
			(at 0 1.17 0)
			(layer "B.SilkS")
			(hide yes)
			(effects
				(font
					(size 0.7 0.7)
					(thickness 0.15)
				)
				(justify left bottom mirror)
			)
		)
		(property "Value" "C_4u7_0402"
			(at 0 -1.169 0)
			(layer "B.Fab")
			(effects
				(font
					(size 0.7 0.7)
					(thickness 0.15)
				)
				(justify left bottom mirror)
			)
		)
		(property "Datasheet" "https://www.murata.com/products/productdetail?partno=GRM155R61A475MEAA%23"
			(at 0 0 180)
			(layer "F.Fab")
			(hide yes)
			(effects
				(font
					(size 1.27 1.27)
					(thickness 0.15)
				)
			)
		)
		(property "Author" "Antmicro"
			(at 283.751002 346.602 0)
			(layer "B.Fab")
			(hide yes)
			(effects
				(font
					(size 1 1)
					(thickness 0.15)
				)
				(justify mirror)
			)
		)
		(property "Dielectric" ""
			(at 283.751002 346.602 0)
			(layer "B.Fab")
			(hide yes)
			(effects
				(font
					(size 1 1)
					(thickness 0.15)
				)
				(justify mirror)
			)
		)
		(property "License" "Apache-2.0"
			(at 283.751002 346.602 0)
			(layer "B.Fab")
			(hide yes)
			(effects
				(font
					(size 1 1)
					(thickness 0.15)
				)
				(justify mirror)
			)
		)
		(property "MPN" "GRM155R61A475MEAAD"
			(at 283.751002 346.602 0)
			(layer "B.Fab")
			(hide yes)
			(effects
				(font
					(size 1 1)
					(thickness 0.15)
				)
				(justify mirror)
			)
		)
		(property "Manufacturer" "Murata"
			(at 283.751002 346.602 0)
			(layer "B.Fab")
			(hide yes)
			(effects
				(font
					(size 1 1)
					(thickness 0.15)
				)
				(justify mirror)
			)
		)
		(property "Val" "4u7"
			(at 283.751002 346.602 0)
			(layer "B.Fab")
			(hide yes)
			(effects
				(font
					(size 1 1)
					(thickness 0.15)
				)
				(justify mirror)
			)
		)
		(property "Voltage" ""
			(at 283.751002 346.602 0)
			(layer "B.Fab")
			(hide yes)
			(effects
				(font
					(size 1 1)
					(thickness 0.15)
				)
				(justify mirror)
			)
		)
		(sheetname "/FPGA power/")
		(sheetfile "fpga-power.kicad_sch")
		(attr smd)
		(fp_rect
			(start -0.9656 0.4572)
			(end 0.9652 -0.4828)
			(stroke
				(width 0.05)
				(type solid)
			)
			(fill no)
			(layer "B.CrtYd")
		)
		(fp_line
			(start 0.498 0.25)
			(end 0.498 -0.248)
			(stroke
				(width 0.15)
				(type solid)
			)
			(layer "B.Fab")
		)
		(fp_line
			(start 0.498 -0.248)
			(end -0.5 -0.248)
			(stroke
				(width 0.15)
				(type solid)
			)
			(layer "B.Fab")
		)
		(fp_line
			(start -0.5 0.25)
			(end 0.498 0.25)
			(stroke
				(width 0.15)
				(type solid)
			)
			(layer "B.Fab")
		)
		(fp_line
			(start -0.5 -0.248)
			(end -0.5 0.25)
			(stroke
				(width 0.15)
				(type solid)
			)
			(layer "B.Fab")
		)
		(pad "1" smd roundrect
			(at -0.5 0 90)
			(size 0.6 0.6)
			(layers "B.Cu" "B.Mask" "B.Paste")
			(roundrect_rratio 0.25)
			(net 188 "+1V8")
			(pintype "passive")
		)
		(pad "2" smd roundrect
			(at 0.498 0 180)
			(size 0.6 0.6)
			(layers "B.Cu" "B.Mask" "B.Paste")
			(roundrect_rratio 0.25)
			(net 1 "GND")
			(pintype "passive")
		)
	)
)
